(kicad_pcb
	(version 20260206)
	(generator "pcbnew")
	(generator_version "10.0")
	(general
		(thickness 1.6)
		(legacy_teardrops no)
	)
	(paper "A4")
	(title_block
		(title "04192023_DAF0TMB3IC0_F0TG_MB_C_brd_V02_OCP.brd")
		(comment 1 "Grand Teton / footprint 34 of 8354 (J37), pads 227-291 of 291")
	)
	(layers
		(0 "F.Cu" signal "TOP")
		(4 "In1.Cu" signal "GND")
		(6 "In2.Cu" signal "IN1")
		(8 "In3.Cu" signal "GND1")
		(10 "In4.Cu" signal "IN2")
		(12 "In5.Cu" signal "GND2")
		(14 "In6.Cu" signal "IN3")
		(16 "In7.Cu" signal "GND3")
		(18 "In8.Cu" signal "VCC")
		(20 "In9.Cu" signal "VCC1")
		(22 "In10.Cu" signal "GND4")
		(24 "In11.Cu" signal "IN4")
		(26 "In12.Cu" signal "GND5")
		(28 "In13.Cu" signal "IN5")
		(30 "In14.Cu" signal "GND6")
		(32 "In15.Cu" signal "IN6")
		(34 "In16.Cu" signal "GND7")
		(2 "B.Cu" signal "BOTTOM")
		(9 "F.Adhes" user "F.Adhesive")
		(11 "B.Adhes" user "B.Adhesive")
		(13 "F.Paste" user "Package Geometry/Pastemask Top")
		(15 "B.Paste" user "Package Geometry/Pastemask Bottom")
		(5 "F.SilkS" user "Ref Des/Silkscreen Top")
		(7 "B.SilkS" user "Ref Des/Silkscreen Bottom")
		(1 "F.Mask" user "Board Geometry/Soldermask Top")
		(3 "B.Mask" user "Board Geometry/Soldermask Bottom")
		(17 "Dwgs.User" user "User.Drawings")
		(19 "Cmts.User" user "User.Comments")
		(21 "Eco1.User" user "User.Eco1")
		(23 "Eco2.User" user "User.Eco2")
		(25 "Edge.Cuts" user "Board Geometry/Outline")
		(27 "Margin" user)
		(31 "F.CrtYd" user "Package Geometry/Place Bound Top")
		(29 "B.CrtYd" user "Package Geometry/Place Bound Bottom")
		(35 "F.Fab" user "Ref Des/Assembly Top")
		(33 "B.Fab" user "Ref Des/Assembly Bottom")
	)
	(footprint ""
		(layer "F.Cu")
		(at 204.197966 -255.560322 180)
		(property "Reference" "J37"
			(at 2.8702 -81.730088 0)
			(unlocked yes)
			(layer "F.SilkS")
			(effects
				(font
					(size 0.7874 0.5842)
					(thickness 0.1524)
				)
			)
		)
		(property "Value" ""
			(at 0 0 180)
			(layer "F.Fab")
			(effects
				(font
					(size 1.27 1.27)
				)
			)
		)
		(duplicate_pad_numbers_are_jumpers no)
		(pad "227" smd rect
			(at 2.050034 11.474958 90)
			(size 0.519938 1.4986)
			(layers "F.Cu" "F.Mask" "F.Paste")
			(net "M_L_CPU1_SB_PAR")
		)
		(pad "228" smd rect
			(at 2.050034 12.325096 90)
			(size 0.519938 1.4986)
			(layers "F.Cu" "F.Mask" "F.Paste")
			(net "GND")
		)
		(pad "229" smd rect
			(at 2.050034 13.17498 90)
			(size 0.519938 1.4986)
			(layers "F.Cu" "F.Mask" "F.Paste")
			(net "M_L_CPU1_SB_CS_N<1>")
		)
		(pad "230" smd rect
			(at 2.050034 14.025118 90)
			(size 0.519938 1.4986)
			(layers "F.Cu" "F.Mask" "F.Paste")
			(net "GND")
		)
		(pad "231" smd rect
			(at 2.050034 14.875002 90)
			(size 0.519938 1.4986)
			(layers "F.Cu" "F.Mask" "F.Paste")
			(net "Net_2415")
		)
		(pad "232" smd rect
			(at 2.050034 15.724886 90)
			(size 0.519938 1.4986)
			(layers "F.Cu" "F.Mask" "F.Paste")
			(net "Net_2416")
		)
		(pad "233" smd rect
			(at 2.050034 16.575024 90)
			(size 0.519938 1.4986)
			(layers "F.Cu" "F.Mask" "F.Paste")
			(net "GND")
		)
		(pad "234" smd rect
			(at 2.050034 17.424908 90)
			(size 0.519938 1.4986)
			(layers "F.Cu" "F.Mask" "F.Paste")
			(net "M_L_CPU1_SB_CB<6>")
		)
		(pad "235" smd rect
			(at 2.050034 18.275046 90)
			(size 0.519938 1.4986)
			(layers "F.Cu" "F.Mask" "F.Paste")
			(net "GND")
		)
		(pad "236" smd rect
			(at 2.050034 19.12493 90)
			(size 0.519938 1.4986)
			(layers "F.Cu" "F.Mask" "F.Paste")
			(net "M_L_CPU1_SB_CB<7>")
		)
		(pad "237" smd rect
			(at 2.050034 19.975068 90)
			(size 0.519938 1.4986)
			(layers "F.Cu" "F.Mask" "F.Paste")
			(net "GND")
		)
		(pad "238" smd rect
			(at 2.050034 20.824952 90)
			(size 0.519938 1.4986)
			(layers "F.Cu" "F.Mask" "F.Paste")
			(net "M_L_CPU1_SB_DQS_DN<4>")
		)
		(pad "239" smd rect
			(at 2.050034 21.67509 90)
			(size 0.519938 1.4986)
			(layers "F.Cu" "F.Mask" "F.Paste")
			(net "M_L_CPU1_SB_DQS_DP<4>")
		)
		(pad "240" smd rect
			(at 2.050034 22.524974 90)
			(size 0.519938 1.4986)
			(layers "F.Cu" "F.Mask" "F.Paste")
			(net "GND")
		)
		(pad "241" smd rect
			(at 2.050034 23.375112 90)
			(size 0.519938 1.4986)
			(layers "F.Cu" "F.Mask" "F.Paste")
			(net "M_L_CPU1_SB_CB<2>")
		)
		(pad "242" smd rect
			(at 2.050034 24.224996 90)
			(size 0.519938 1.4986)
			(layers "F.Cu" "F.Mask" "F.Paste")
			(net "GND")
		)
		(pad "243" smd rect
			(at 2.050034 25.07488 90)
			(size 0.519938 1.4986)
			(layers "F.Cu" "F.Mask" "F.Paste")
			(net "M_L_CPU1_SB_CB<3>")
		)
		(pad "244" smd rect
			(at 2.050034 25.925018 90)
			(size 0.519938 1.4986)
			(layers "F.Cu" "F.Mask" "F.Paste")
			(net "GND")
		)
		(pad "245" smd rect
			(at 2.050034 26.774902 90)
			(size 0.519938 1.4986)
			(layers "F.Cu" "F.Mask" "F.Paste")
			(net "M_L_CPU1_SB_DQ<2>")
		)
		(pad "246" smd rect
			(at 2.050034 27.62504 90)
			(size 0.519938 1.4986)
			(layers "F.Cu" "F.Mask" "F.Paste")
			(net "GND")
		)
		(pad "247" smd rect
			(at 2.050034 28.474924 90)
			(size 0.519938 1.4986)
			(layers "F.Cu" "F.Mask" "F.Paste")
			(net "M_L_CPU1_SB_DQ<3>")
		)
		(pad "248" smd rect
			(at 2.050034 29.325062 90)
			(size 0.519938 1.4986)
			(layers "F.Cu" "F.Mask" "F.Paste")
			(net "GND")
		)
		(pad "249" smd rect
			(at 2.050034 30.174946 90)
			(size 0.519938 1.4986)
			(layers "F.Cu" "F.Mask" "F.Paste")
			(net "M_L_CPU1_SB_DQS_DN<5>")
		)
		(pad "250" smd rect
			(at 2.050034 31.025084 90)
			(size 0.519938 1.4986)
			(layers "F.Cu" "F.Mask" "F.Paste")
			(net "M_L_CPU1_SB_DQS_DP<5>")
		)
		(pad "251" smd rect
			(at 2.050034 31.874968 90)
			(size 0.519938 1.4986)
			(layers "F.Cu" "F.Mask" "F.Paste")
			(net "GND")
		)
		(pad "252" smd rect
			(at 2.050034 32.725106 90)
			(size 0.519938 1.4986)
			(layers "F.Cu" "F.Mask" "F.Paste")
			(net "M_L_CPU1_SB_DQ<6>")
		)
		(pad "253" smd rect
			(at 2.050034 33.57499 90)
			(size 0.519938 1.4986)
			(layers "F.Cu" "F.Mask" "F.Paste")
			(net "GND")
		)
		(pad "254" smd rect
			(at 2.050034 34.425128 90)
			(size 0.519938 1.4986)
			(layers "F.Cu" "F.Mask" "F.Paste")
			(net "M_L_CPU1_SB_DQ<7>")
		)
		(pad "255" smd rect
			(at 2.050034 35.275012 90)
			(size 0.519938 1.4986)
			(layers "F.Cu" "F.Mask" "F.Paste")
			(net "GND")
		)
		(pad "256" smd rect
			(at 2.050034 36.124896 90)
			(size 0.519938 1.4986)
			(layers "F.Cu" "F.Mask" "F.Paste")
			(net "M_L_CPU1_SB_DQ<10>")
		)
		(pad "257" smd rect
			(at 2.050034 36.975034 90)
			(size 0.519938 1.4986)
			(layers "F.Cu" "F.Mask" "F.Paste")
			(net "GND")
		)
		(pad "258" smd rect
			(at 2.050034 37.824918 90)
			(size 0.519938 1.4986)
			(layers "F.Cu" "F.Mask" "F.Paste")
			(net "M_L_CPU1_SB_DQ<11>")
		)
		(pad "259" smd rect
			(at 2.050034 38.675056 90)
			(size 0.519938 1.4986)
			(layers "F.Cu" "F.Mask" "F.Paste")
			(net "GND")
		)
		(pad "260" smd rect
			(at 2.050034 39.52494 90)
			(size 0.519938 1.4986)
			(layers "F.Cu" "F.Mask" "F.Paste")
			(net "M_L_CPU1_SB_DQS_DN<6>")
		)
		(pad "261" smd rect
			(at 2.050034 40.375078 90)
			(size 0.519938 1.4986)
			(layers "F.Cu" "F.Mask" "F.Paste")
			(net "M_L_CPU1_SB_DQS_DP<6>")
		)
		(pad "262" smd rect
			(at 2.050034 41.224962 90)
			(size 0.519938 1.4986)
			(layers "F.Cu" "F.Mask" "F.Paste")
			(net "GND")
		)
		(pad "263" smd rect
			(at 2.050034 42.0751 90)
			(size 0.519938 1.4986)
			(layers "F.Cu" "F.Mask" "F.Paste")
			(net "M_L_CPU1_SB_DQ<14>")
		)
		(pad "264" smd rect
			(at 2.050034 42.924984 90)
			(size 0.519938 1.4986)
			(layers "F.Cu" "F.Mask" "F.Paste")
			(net "GND")
		)
		(pad "265" smd rect
			(at 2.050034 43.775122 90)
			(size 0.519938 1.4986)
			(layers "F.Cu" "F.Mask" "F.Paste")
			(net "M_L_CPU1_SB_DQ<15>")
		)
		(pad "266" smd rect
			(at 2.050034 44.625006 90)
			(size 0.519938 1.4986)
			(layers "F.Cu" "F.Mask" "F.Paste")
			(net "GND")
		)
		(pad "267" smd rect
			(at 2.050034 45.47489 90)
			(size 0.519938 1.4986)
			(layers "F.Cu" "F.Mask" "F.Paste")
			(net "M_L_CPU1_SB_DQ<18>")
		)
		(pad "268" smd rect
			(at 2.050034 46.325028 90)
			(size 0.519938 1.4986)
			(layers "F.Cu" "F.Mask" "F.Paste")
			(net "GND")
		)
		(pad "269" smd rect
			(at 2.050034 47.174912 90)
			(size 0.519938 1.4986)
			(layers "F.Cu" "F.Mask" "F.Paste")
			(net "M_L_CPU1_SB_DQ<19>")
		)
		(pad "270" smd rect
			(at 2.050034 48.02505 90)
			(size 0.519938 1.4986)
			(layers "F.Cu" "F.Mask" "F.Paste")
			(net "GND")
		)
		(pad "271" smd rect
			(at 2.050034 48.874934 90)
			(size 0.519938 1.4986)
			(layers "F.Cu" "F.Mask" "F.Paste")
			(net "M_L_CPU1_SB_DQS_DN<7>")
		)
		(pad "272" smd rect
			(at 2.050034 49.725072 90)
			(size 0.519938 1.4986)
			(layers "F.Cu" "F.Mask" "F.Paste")
			(net "M_L_CPU1_SB_DQS_DP<7>")
		)
		(pad "273" smd rect
			(at 2.050034 50.574956 90)
			(size 0.519938 1.4986)
			(layers "F.Cu" "F.Mask" "F.Paste")
			(net "GND")
		)
		(pad "274" smd rect
			(at 2.050034 51.425094 90)
			(size 0.519938 1.4986)
			(layers "F.Cu" "F.Mask" "F.Paste")
			(net "M_L_CPU1_SB_DQ<22>")
		)
		(pad "275" smd rect
			(at 2.050034 52.274978 90)
			(size 0.519938 1.4986)
			(layers "F.Cu" "F.Mask" "F.Paste")
			(net "GND")
		)
		(pad "276" smd rect
			(at 2.050034 53.125116 90)
			(size 0.519938 1.4986)
			(layers "F.Cu" "F.Mask" "F.Paste")
			(net "M_L_CPU1_SB_DQ<23>")
		)
		(pad "277" smd rect
			(at 2.050034 53.975 90)
			(size 0.519938 1.4986)
			(layers "F.Cu" "F.Mask" "F.Paste")
			(net "GND")
		)
		(pad "278" smd rect
			(at 2.050034 54.824884 90)
			(size 0.519938 1.4986)
			(layers "F.Cu" "F.Mask" "F.Paste")
			(net "M_L_CPU1_SB_DQ<26>")
		)
		(pad "279" smd rect
			(at 2.050034 55.675022 90)
			(size 0.519938 1.4986)
			(layers "F.Cu" "F.Mask" "F.Paste")
			(net "GND")
		)
		(pad "280" smd rect
			(at 2.050034 56.524906 90)
			(size 0.519938 1.4986)
			(layers "F.Cu" "F.Mask" "F.Paste")
			(net "M_L_CPU1_SB_DQ<27>")
		)
		(pad "281" smd rect
			(at 2.050034 57.375044 90)
			(size 0.519938 1.4986)
			(layers "F.Cu" "F.Mask" "F.Paste")
			(net "GND")
		)
		(pad "282" smd rect
			(at 2.050034 58.224928 90)
			(size 0.519938 1.4986)
			(layers "F.Cu" "F.Mask" "F.Paste")
			(net "M_L_CPU1_SB_DQS_DN<8>")
		)
		(pad "283" smd rect
			(at 2.050034 59.075066 90)
			(size 0.519938 1.4986)
			(layers "F.Cu" "F.Mask" "F.Paste")
			(net "M_L_CPU1_SB_DQS_DP<8>")
		)
		(pad "284" smd rect
			(at 2.050034 59.92495 90)
			(size 0.519938 1.4986)
			(layers "F.Cu" "F.Mask" "F.Paste")
			(net "GND")
		)
		(pad "285" smd rect
			(at 2.050034 60.775088 90)
			(size 0.519938 1.4986)
			(layers "F.Cu" "F.Mask" "F.Paste")
			(net "M_L_CPU1_SB_DQ<30>")
		)
		(pad "286" smd rect
			(at 2.050034 61.624972 90)
			(size 0.519938 1.4986)
			(layers "F.Cu" "F.Mask" "F.Paste")
			(net "GND")
		)
		(pad "287" smd rect
			(at 2.050034 62.47511 90)
			(size 0.519938 1.4986)
			(layers "F.Cu" "F.Mask" "F.Paste")
			(net "M_L_CPU1_SB_DQ<31>")
		)
		(pad "288" smd rect
			(at 2.050034 63.324994 90)
			(size 0.519938 1.4986)
			(layers "F.Cu" "F.Mask" "F.Paste")
			(net "GND")
		)
		(pad "G1" thru_hole oval
			(at 0 -68.97497 90)
			(size 1.7272 3.4798)
			(drill oval 1.2192 2.4638)
			(layers "*.Cu" "*.Mask")
			(remove_unused_layers no)
			(net "GND")
			(clearance 0.127)
			(thermal_gap 0.127)
		)
		(pad "G2" thru_hole oval
			(at 0 3.875024 90)
			(size 1.7272 3.4798)
			(drill oval 1.2192 2.4638)
			(layers "*.Cu" "*.Mask")
			(remove_unused_layers no)
			(net "GND")
			(clearance 0.127)
			(thermal_gap 0.127)
		)
		(pad "G3" thru_hole oval
			(at 0 68.97497 90)
			(size 1.7272 3.4798)
			(drill oval 1.2192 2.4638)
			(layers "*.Cu" "*.Mask")
			(remove_unused_layers no)
			(net "GND")
			(clearance 0.127)
			(thermal_gap 0.127)
		)
	)
)
